(kicad_pcb
	(version 20260206)
	(generator "pcbnew")
	(generator_version "10.0")
	(general
		(thickness 1.6)
		(legacy_teardrops no)
	)
	(paper "A4")
	(title_block
		(title "v1-pdb — T6M_PDB_D_0927_0900.brd")
		(comment 1 "Open CloudServer (Microsoft) / footprints 247-251 of 321")
	)
	(layers
		(0 "F.Cu" signal "TOP")
		(4 "In1.Cu" signal "GND")
		(6 "In2.Cu" signal "IN1")
		(8 "In3.Cu" signal "VCC")
		(10 "In4.Cu" signal "VCC1")
		(12 "In5.Cu" signal "IN2")
		(14 "In6.Cu" signal "GND1")
		(2 "B.Cu" signal "BOTTOM")
		(9 "F.Adhes" user "F.Adhesive")
		(11 "B.Adhes" user "B.Adhesive")
		(13 "F.Paste" user "Package Geometry/Pastemask Top")
		(15 "B.Paste" user "Package Geometry/Pastemask Bottom")
		(5 "F.SilkS" user "Ref Des/Silkscreen Top")
		(7 "B.SilkS" user "Ref Des/Silkscreen Bottom")
		(1 "F.Mask" user "Board Geometry/Soldermask Top")
		(3 "B.Mask" user "Board Geometry/Soldermask Bottom")
		(17 "Dwgs.User" user "User.Drawings")
		(19 "Cmts.User" user "User.Comments")
		(21 "Eco1.User" user "User.Eco1")
		(23 "Eco2.User" user "User.Eco2")
		(25 "Edge.Cuts" user "Board Geometry/Outline")
		(27 "Margin" user)
		(31 "F.CrtYd" user "Package Geometry/Place Bound Top")
		(29 "B.CrtYd" user "Package Geometry/Place Bound Bottom")
		(35 "F.Fab" user "Ref Des/Assembly Top")
		(33 "B.Fab" user "Ref Des/Assembly Bottom")
	)
	(footprint ""
		(layer "F.Cu")
		(at 49.949354 -107.119928 180)
		(property "Reference" "CE5"
			(at -5.215128 0.67437 0)
			(unlocked yes)
			(layer "F.SilkS")
			(effects
				(font
					(size 0.7874 0.5842)
					(thickness 0.1524)
				)
				(justify left)
			)
		)
		(property "Value" ""
			(at 0 0 180)
			(layer "F.Fab")
			(effects
				(font
					(size 1.27 1.27)
				)
			)
		)
		(duplicate_pad_numbers_are_jumpers no)
		(fp_line
			(start 0 -4.2672)
			(end 0 4.2672)
			(stroke
				(width 0.1524)
				(type default)
			)
			(layer "F.SilkS")
		)
		(fp_circle
			(center 0 0)
			(end -4.2672 0)
			(stroke
				(width 0.1524)
				(type default)
			)
			(fill no)
			(layer "F.SilkS")
		)
		(fp_poly
			(pts
				(arc
					(start 0 -4.2672)
					(mid 4.2672 0)
					(end 0 4.2672)
				)
			)
			(stroke
				(width 0)
				(type default)
			)
			(fill yes)
			(layer "F.SilkS")
		)
		(fp_poly
			(pts
				(xy -2.5146 -0.762) (xy -0.9906 -0.762) (xy -0.9906 0.762) (xy -2.5146 0.762)
			)
			(stroke
				(width 0)
				(type default)
			)
			(fill no)
			(layer "B.CrtYd")
		)
		(fp_poly
			(pts
				(arc
					(start 1.7526 0.762)
					(mid 2.291415 -0.538815)
					(end 0.9906 0)
				)
				(arc
					(start 0.9906 0.0254)
					(mid 1.206345 0.546255)
					(end 1.7272 0.762)
				)
			)
			(stroke
				(width 0)
				(type default)
			)
			(fill no)
			(layer "B.CrtYd")
		)
		(fp_poly
			(pts
				(arc
					(start -4.2672 0)
					(mid 4.2672 0)
					(end -4.2672 0)
				)
			)
			(stroke
				(width 0)
				(type default)
			)
			(fill no)
			(layer "F.CrtYd")
		)
		(fp_circle
			(center 0 0)
			(end -4.2672 0)
			(stroke
				(width 0.1)
				(type default)
			)
			(fill no)
			(layer "F.Fab")
		)
		(fp_text user "+"
			(at -5.033772 -1.421384 180)
			(unlocked yes)
			(layer "F.SilkS")
			(effects
				(font
					(size 0.7874 0.5842)
					(thickness 0.1524)
				)
				(justify left)
			)
		)
		(fp_text user "+"
			(at -5.6642 -0.34925 180)
			(unlocked yes)
			(layer "F.Fab")
			(effects
				(font
					(size 1.905 1.4224)
					(thickness 0.000001)
				)
				(justify left)
			)
		)
		(pad "1" thru_hole rect
			(at -1.75006 0 180)
			(size 1.397 1.397)
			(drill 0.9144)
			(layers "*.Cu" "*.Mask")
			(remove_unused_layers no)
			(net "P12V")
			(clearance 0.0127)
			(thermal_gap 0.0127)
			(padstack
				(mode front_inner_back)
				(layer "Inner"
					(shape circle)
					(size 1.397 1.397)
					(clearance 0.0127)
				)
				(layer "B.Cu"
					(shape rect)
					(size 1.397 1.397)
					(clearance 0.0127)
				)
			)
		)
		(pad "2" thru_hole circle
			(at 1.75006 0 180)
			(size 1.397 1.397)
			(drill 0.9144)
			(layers "*.Cu" "*.Mask")
			(remove_unused_layers no)
			(net "GND")
			(clearance 0.0127)
			(thermal_gap 0.0127)
		)
	)
	(footprint ""
		(layer "F.Cu")
		(at 16.017494 -330.497434 -90)
		(property "Reference" "R38"
			(at 3.685032 -0.234188 90)
			(unlocked yes)
			(layer "F.SilkS")
			(effects
				(font
					(size 0.7874 0.5842)
					(thickness 0.1524)
				)
				(justify left)
			)
		)
		(property "Value" ""
			(at 0 0 270)
			(layer "F.Fab")
			(effects
				(font
					(size 1.27 1.27)
				)
			)
		)
		(duplicate_pad_numbers_are_jumpers no)
		(fp_line
			(start -0.7874 0.4064)
			(end -0.7874 -0.4064)
			(stroke
				(width 0.1524)
				(type default)
			)
			(layer "F.SilkS")
		)
		(fp_line
			(start 0.7874 0.4064)
			(end -0.7874 0.4064)
			(stroke
				(width 0.1524)
				(type default)
			)
			(layer "F.SilkS")
		)
		(fp_line
			(start -0.7874 -0.4064)
			(end 0.7874 -0.4064)
			(stroke
				(width 0.1524)
				(type default)
			)
			(layer "F.SilkS")
		)
		(fp_line
			(start 0.7874 -0.4064)
			(end 0.7874 0.4064)
			(stroke
				(width 0.1524)
				(type default)
			)
			(layer "F.SilkS")
		)
		(fp_poly
			(pts
				(xy -0.508 0.2794) (xy -0.508 0.2286) (xy -0.635 0.2286) (xy -0.635 -0.254) (xy -0.5334 -0.254)
				(xy -0.5334 -0.2794) (xy 0.5334 -0.2794) (xy 0.5334 -0.254) (xy 0.635 -0.254) (xy 0.635 0.254) (xy 0.5334 0.254)
				(xy 0.5334 0.2794)
			)
			(stroke
				(width 0)
				(type default)
			)
			(fill no)
			(layer "F.CrtYd")
		)
		(pad "1" smd rect
			(at 0.40005 0 270)
			(size 0.4572 0.508)
			(layers "F.Cu" "F.Mask" "F.Paste")
			(net "GND")
		)
		(pad "2" smd rect
			(at -0.40005 0 270)
			(size 0.4572 0.508)
			(layers "F.Cu" "F.Mask" "F.Paste")
			(net "FRU_A1")
		)
	)
	(footprint ""
		(layer "F.Cu")
		(at 50.417984 -217.485976 180)
		(property "Reference" "CE11"
			(at -4.932426 0.531114 0)
			(unlocked yes)
			(layer "F.SilkS")
			(effects
				(font
					(size 0.7874 0.5842)
					(thickness 0.1524)
				)
				(justify left)
			)
		)
		(property "Value" ""
			(at 0 0 180)
			(layer "F.Fab")
			(effects
				(font
					(size 1.27 1.27)
				)
			)
		)
		(duplicate_pad_numbers_are_jumpers no)
		(fp_line
			(start 0 -4.2672)
			(end 0 4.2672)
			(stroke
				(width 0.1524)
				(type default)
			)
			(layer "F.SilkS")
		)
		(fp_circle
			(center 0 0)
			(end -4.2672 0)
			(stroke
				(width 0.1524)
				(type default)
			)
			(fill no)
			(layer "F.SilkS")
		)
		(fp_poly
			(pts
				(arc
					(start 0 -4.2672)
					(mid 4.2672 0)
					(end 0 4.2672)
				)
			)
			(stroke
				(width 0)
				(type default)
			)
			(fill yes)
			(layer "F.SilkS")
		)
		(fp_poly
			(pts
				(xy -2.5146 -0.762) (xy -0.9906 -0.762) (xy -0.9906 0.762) (xy -2.5146 0.762)
			)
			(stroke
				(width 0)
				(type default)
			)
			(fill no)
			(layer "B.CrtYd")
		)
		(fp_poly
			(pts
				(arc
					(start 1.7526 0.762)
					(mid 2.291415 -0.538815)
					(end 0.9906 0)
				)
				(arc
					(start 0.9906 0.0254)
					(mid 1.206345 0.546255)
					(end 1.7272 0.762)
				)
			)
			(stroke
				(width 0)
				(type default)
			)
			(fill no)
			(layer "B.CrtYd")
		)
		(fp_poly
			(pts
				(arc
					(start -4.2672 0)
					(mid 4.2672 0)
					(end -4.2672 0)
				)
			)
			(stroke
				(width 0)
				(type default)
			)
			(fill no)
			(layer "F.CrtYd")
		)
		(fp_circle
			(center 0 0)
			(end -4.2672 0)
			(stroke
				(width 0.1)
				(type default)
			)
			(fill no)
			(layer "F.Fab")
		)
		(fp_text user "+"
			(at -6.029198 -0.758698 180)
			(unlocked yes)
			(layer "F.SilkS")
			(effects
				(font
					(size 0.7874 0.5842)
					(thickness 0.1524)
				)
				(justify left)
			)
		)
		(fp_text user "+"
			(at -5.6642 -0.34925 180)
			(unlocked yes)
			(layer "F.Fab")
			(effects
				(font
					(size 1.905 1.4224)
					(thickness 0.000001)
				)
				(justify left)
			)
		)
		(pad "1" thru_hole rect
			(at -1.75006 0 180)
			(size 1.397 1.397)
			(drill 0.9144)
			(layers "*.Cu" "*.Mask")
			(remove_unused_layers no)
			(net "P12V")
			(clearance 0.0127)
			(thermal_gap 0.0127)
			(padstack
				(mode front_inner_back)
				(layer "Inner"
					(shape circle)
					(size 1.397 1.397)
					(clearance 0.0127)
				)
				(layer "B.Cu"
					(shape rect)
					(size 1.397 1.397)
					(clearance 0.0127)
				)
			)
		)
		(pad "2" thru_hole circle
			(at 1.75006 0 180)
			(size 1.397 1.397)
			(drill 0.9144)
			(layers "*.Cu" "*.Mask")
			(remove_unused_layers no)
			(net "GND")
			(clearance 0.0127)
			(thermal_gap 0.0127)
		)
	)
	(footprint ""
		(layer "F.Cu")
		(at 50.083466 -38.6207 180)
		(property "Reference" "CE2"
			(at 1.317244 -5.56133 0)
			(unlocked yes)
			(layer "F.SilkS")
			(effects
				(font
					(size 0.7874 0.5842)
					(thickness 0.1524)
				)
				(justify left)
			)
		)
		(property "Value" ""
			(at 0 0 180)
			(layer "F.Fab")
			(effects
				(font
					(size 1.27 1.27)
				)
			)
		)
		(duplicate_pad_numbers_are_jumpers no)
		(fp_line
			(start 0 -4.2672)
			(end 0 4.2672)
			(stroke
				(width 0.1524)
				(type default)
			)
			(layer "F.SilkS")
		)
		(fp_circle
			(center 0 0)
			(end -4.2672 0)
			(stroke
				(width 0.1524)
				(type default)
			)
			(fill no)
			(layer "F.SilkS")
		)
		(fp_poly
			(pts
				(arc
					(start 0 -4.2672)
					(mid 4.2672 0)
					(end 0 4.2672)
				)
			)
			(stroke
				(width 0)
				(type default)
			)
			(fill yes)
			(layer "F.SilkS")
		)
		(fp_poly
			(pts
				(xy -2.5146 -0.762) (xy -0.9906 -0.762) (xy -0.9906 0.762) (xy -2.5146 0.762)
			)
			(stroke
				(width 0)
				(type default)
			)
			(fill no)
			(layer "B.CrtYd")
		)
		(fp_poly
			(pts
				(arc
					(start 1.7526 0.762)
					(mid 2.291415 -0.538815)
					(end 0.9906 0)
				)
				(arc
					(start 0.9906 0.0254)
					(mid 1.206345 0.546255)
					(end 1.7272 0.762)
				)
			)
			(stroke
				(width 0)
				(type default)
			)
			(fill no)
			(layer "B.CrtYd")
		)
		(fp_poly
			(pts
				(arc
					(start -4.2672 0)
					(mid 4.2672 0)
					(end -4.2672 0)
				)
			)
			(stroke
				(width 0)
				(type default)
			)
			(fill no)
			(layer "F.CrtYd")
		)
		(fp_circle
			(center 0 0)
			(end -4.2672 0)
			(stroke
				(width 0.1)
				(type default)
			)
			(fill no)
			(layer "F.Fab")
		)
		(fp_text user "+"
			(at -3.633216 3.210814 180)
			(unlocked yes)
			(layer "F.SilkS")
			(effects
				(font
					(size 0.7874 0.5842)
					(thickness 0.1524)
				)
				(justify left)
			)
		)
		(fp_text user "+"
			(at -5.6642 -0.34925 180)
			(unlocked yes)
			(layer "F.Fab")
			(effects
				(font
					(size 1.905 1.4224)
					(thickness 0.000001)
				)
				(justify left)
			)
		)
		(pad "1" thru_hole rect
			(at -1.75006 0 180)
			(size 1.397 1.397)
			(drill 0.9144)
			(layers "*.Cu" "*.Mask")
			(remove_unused_layers no)
			(net "P12V")
			(clearance 0.0127)
			(thermal_gap 0.0127)
			(padstack
				(mode front_inner_back)
				(layer "Inner"
					(shape circle)
					(size 1.397 1.397)
					(clearance 0.0127)
				)
				(layer "B.Cu"
					(shape rect)
					(size 1.397 1.397)
					(clearance 0.0127)
				)
			)
		)
		(pad "2" thru_hole circle
			(at 1.75006 0 180)
			(size 1.397 1.397)
			(drill 0.9144)
			(layers "*.Cu" "*.Mask")
			(remove_unused_layers no)
			(net "GND")
			(clearance 0.0127)
			(thermal_gap 0.0127)
		)
	)
	(footprint ""
		(layer "F.Cu")
		(at 26.850848 -19.859244)
		(property "Reference" "R5"
			(at -2.617978 0.04699 0)
			(unlocked yes)
			(layer "F.SilkS")
			(effects
				(font
					(size 0.7874 0.5842)
					(thickness 0.1524)
				)
				(justify left)
			)
		)
		(property "Value" ""
			(at 0 0 0)
			(layer "F.Fab")
			(effects
				(font
					(size 1.27 1.27)
				)
			)
		)
		(duplicate_pad_numbers_are_jumpers no)
		(fp_line
			(start -0.7874 -0.4064)
			(end 0.7874 -0.4064)
			(stroke
				(width 0.1524)
				(type default)
			)
			(layer "F.SilkS")
		)
		(fp_line
			(start -0.7874 0.4064)
			(end -0.7874 -0.4064)
			(stroke
				(width 0.1524)
				(type default)
			)
			(layer "F.SilkS")
		)
		(fp_line
			(start 0.7874 -0.4064)
			(end 0.7874 0.4064)
			(stroke
				(width 0.1524)
				(type default)
			)
			(layer "F.SilkS")
		)
		(fp_line
			(start 0.7874 0.4064)
			(end -0.7874 0.4064)
			(stroke
				(width 0.1524)
				(type default)
			)
			(layer "F.SilkS")
		)
		(fp_poly
			(pts
				(xy -0.508 0.2794) (xy -0.508 0.2286) (xy -0.635 0.2286) (xy -0.635 -0.254) (xy -0.5334 -0.254)
				(xy -0.5334 -0.2794) (xy 0.5334 -0.2794) (xy 0.5334 -0.254) (xy 0.635 -0.254) (xy 0.635 0.254) (xy 0.5334 0.254)
				(xy 0.5334 0.2794)
			)
			(stroke
				(width 0)
				(type default)
			)
			(fill no)
			(layer "F.CrtYd")
		)
		(pad "1" smd rect
			(at 0.40005 0)
			(size 0.4572 0.508)
			(layers "F.Cu" "F.Mask" "F.Paste")
			(net "PSU1_REMOTE_N")
		)
		(pad "2" smd rect
			(at -0.40005 0)
			(size 0.4572 0.508)
			(layers "F.Cu" "F.Mask" "F.Paste")
			(net "GND")
		)
	)
)
